(kicad_pcb
	(version 20260206)
	(generator "pcbnew")
	(generator_version "10.0")
	(general
		(thickness 1.6)
		(legacy_teardrops no)
	)
	(paper "A4")
	(title_block
		(title "pdpb — Lightning_PDPB_BRD.brd")
		(comment 1 "Lightning (Wiwynn / Facebook NVMe JBOF) / footprints 123-129 of 1140")
	)
	(layers
		(0 "F.Cu" signal "TOP")
		(4 "In1.Cu" signal "L2GND")
		(6 "In2.Cu" signal "L3")
		(8 "In3.Cu" signal "L4VCC")
		(10 "In4.Cu" signal "L5VCC")
		(12 "In5.Cu" signal "L6")
		(14 "In6.Cu" signal "L7GND")
		(2 "B.Cu" signal "BOTTOM")
		(9 "F.Adhes" user "F.Adhesive")
		(11 "B.Adhes" user "B.Adhesive")
		(13 "F.Paste" user "Package Geometry/Pastemask Top")
		(15 "B.Paste" user "Package Geometry/Pastemask Bottom")
		(5 "F.SilkS" user "Ref Des/Silkscreen Top")
		(7 "B.SilkS" user "Ref Des/Silkscreen Bottom")
		(1 "F.Mask" user "Board Geometry/Soldermask Top")
		(3 "B.Mask" user "Board Geometry/Soldermask Bottom")
		(17 "Dwgs.User" user "User.Drawings")
		(19 "Cmts.User" user "User.Comments")
		(21 "Eco1.User" user "User.Eco1")
		(23 "Eco2.User" user "User.Eco2")
		(25 "Edge.Cuts" user "Board Geometry/Outline")
		(27 "Margin" user)
		(31 "F.CrtYd" user "Package Geometry/Place Bound Top")
		(29 "B.CrtYd" user "Package Geometry/Place Bound Bottom")
		(35 "F.Fab" user "Ref Des/Assembly Top")
		(33 "B.Fab" user "Ref Des/Assembly Bottom")
	)
	(footprint ""
		(layer "F.Cu")
		(at 214.757 -294.894 -90)
		(property "Reference" "U11"
			(at 0 0 270)
			(layer "F.SilkS")
			(hide yes)
			(effects
				(font
					(size 1.27 1.27)
				)
			)
		)
		(property "Value" "P2003EVG-GP"
			(at 0 -11.1252 270)
			(unlocked yes)
			(layer "F.Fab")
			(hide yes)
			(effects
				(font
					(size 1.016 1.016)
					(thickness 0.1524)
				)
			)
		)
		(property "Device Type" "SOIC8H79"
			(at 0 -12.6492 270)
			(unlocked yes)
			(layer "F.Fab")
			(hide yes)
			(effects
				(font
					(size 1.016 1.016)
					(thickness 0.1524)
				)
			)
		)
		(duplicate_pad_numbers_are_jumpers no)
		(fp_line
			(start -2.6162 3.429)
			(end -2.6162 1.4732)
			(stroke
				(width 0.4064)
				(type default)
			)
			(layer "F.SilkS")
		)
		(fp_line
			(start -2.7432 1.4224)
			(end 2.1336 1.4224)
			(stroke
				(width 0.1524)
				(type default)
			)
			(layer "F.SilkS")
		)
		(fp_line
			(start 2.1336 1.4224)
			(end 2.1336 -1.4224)
			(stroke
				(width 0.1524)
				(type default)
			)
			(layer "F.SilkS")
		)
		(fp_line
			(start -2.2352 0)
			(end -2.7432 0.508)
			(stroke
				(width 0.1524)
				(type default)
			)
			(layer "F.SilkS")
		)
		(fp_line
			(start -2.7432 -0.508)
			(end -2.2352 0)
			(stroke
				(width 0.1524)
				(type default)
			)
			(layer "F.SilkS")
		)
		(fp_line
			(start -2.7432 -1.4224)
			(end -2.7432 1.4224)
			(stroke
				(width 0.1524)
				(type default)
			)
			(layer "F.SilkS")
		)
		(fp_line
			(start 2.1336 -1.4224)
			(end -2.7432 -1.4224)
			(stroke
				(width 0.1524)
				(type default)
			)
			(layer "F.SilkS")
		)
		(fp_poly
			(pts
				(xy 2.2098 -1.4224) (xy 2.2098 1.4224) (xy -2.2225 1.4224) (xy -2.2225 -1.4224)
			)
			(stroke
				(width 0)
				(type default)
			)
			(fill yes)
			(layer "F.SilkS")
		)
		(fp_rect
			(start -2.4511 2.9972)
			(end 2.4511 -2.9972)
			(stroke
				(width 0)
				(type default)
			)
			(fill no)
			(layer "F.CrtYd")
		)
		(fp_poly
			(pts
				(xy -2.8194 3.6322) (xy -2.8194 -3.6322) (xy 2.8194 -3.6322) (xy 2.8194 -2.2987) (xy 2.4511 -2.2987)
				(xy 2.4511 -2.9972) (xy -2.4511 -2.9972) (xy -2.4511 2.9972) (xy 2.4511 2.9972) (xy 2.4511 -2.286)
				(xy 2.8194 -2.286) (xy 2.8194 3.6322)
			)
			(stroke
				(width 0)
				(type default)
			)
			(fill no)
			(layer "F.CrtYd")
		)
		(fp_rect
			(start -2.8194 3.6322)
			(end 2.8194 -3.6322)
			(stroke
				(width 0)
				(type default)
			)
			(fill no)
			(layer "F.Fab")
		)
		(pad "1" smd rect
			(at -1.905 2.54 270)
			(size 0.635 1.651)
			(layers "F.Cu" "F.Mask" "F.Paste")
			(net "P12V")
		)
		(pad "2" smd rect
			(at -0.635 2.54 270)
			(size 0.635 1.651)
			(layers "F.Cu" "F.Mask" "F.Paste")
			(net "P12V")
		)
		(pad "3" smd rect
			(at 0.635 2.54 270)
			(size 0.635 1.651)
			(layers "F.Cu" "F.Mask" "F.Paste")
			(net "P12V")
		)
		(pad "4" smd rect
			(at 1.905 2.54 270)
			(size 0.635 1.651)
			(layers "F.Cu" "F.Mask" "F.Paste")
			(net "SW_SSD2_N")
		)
		(pad "5" smd rect
			(at 1.905 -2.54 270)
			(size 0.635 1.651)
			(layers "F.Cu" "F.Mask" "F.Paste")
			(net "P12V_SSD2")
		)
		(pad "6" smd rect
			(at 0.635 -2.54 270)
			(size 0.635 1.651)
			(layers "F.Cu" "F.Mask" "F.Paste")
			(net "P12V_SSD2")
		)
		(pad "7" smd rect
			(at -0.635 -2.54 270)
			(size 0.635 1.651)
			(layers "F.Cu" "F.Mask" "F.Paste")
			(net "P12V_SSD2")
		)
		(pad "8" smd rect
			(at -1.905 -2.54 270)
			(size 0.635 1.651)
			(layers "F.Cu" "F.Mask" "F.Paste")
			(net "P12V_SSD2")
		)
	)
	(footprint ""
		(layer "F.Cu")
		(at 78.105 -354.076 180)
		(property "Reference" "SR1154"
			(at 0 0 180)
			(layer "F.SilkS")
			(hide yes)
			(effects
				(font
					(size 1.27 1.27)
				)
			)
		)
		(property "Value" "4K7R2F-GP"
			(at 0.064008 -3.993896 180)
			(unlocked yes)
			(layer "F.Fab")
			(hide yes)
			(effects
				(font
					(size 1.016 1.016)
					(thickness 0.1524)
				)
			)
		)
		(property "Device Type" "R402H16"
			(at 0.064008 -5.517896 180)
			(unlocked yes)
			(layer "F.Fab")
			(hide yes)
			(effects
				(font
					(size 1.016 1.016)
					(thickness 0.1524)
				)
			)
		)
		(duplicate_pad_numbers_are_jumpers no)
		(fp_line
			(start 0.508 -0.9398)
			(end -0.508 -0.9398)
			(stroke
				(width 0.1524)
				(type default)
			)
			(layer "F.SilkS")
		)
		(fp_line
			(start -0.508 -0.9398)
			(end -0.508 0.9398)
			(stroke
				(width 0.1524)
				(type default)
			)
			(layer "F.SilkS")
		)
		(fp_rect
			(start -0.508 0.9398)
			(end 0.508 -0.9398)
			(stroke
				(width 0)
				(type default)
			)
			(fill no)
			(layer "F.CrtYd")
		)
		(fp_rect
			(start -0.508 0.9398)
			(end 0.508 -0.9398)
			(stroke
				(width 0)
				(type default)
			)
			(fill no)
			(layer "F.Fab")
		)
		(pad "1" smd custom
			(at 0 -0.4445 180)
			(size 0.1397 0.1397)
			(layers "F.Cu" "F.Mask" "F.Paste")
			(net "P3V3")
			(options
				(clearance outline)
				(anchor circle)
			)
			(primitives
				(gr_poly
					(pts
						(arc
							(start -0.1778 -0.2794)
							(mid -0.249642 -0.249642)
							(end -0.2794 -0.1778)
						)
						(arc
							(start -0.2794 0.1778)
							(mid -0.249642 0.249642)
							(end -0.1778 0.2794)
						)
						(arc
							(start 0.1778 0.2794)
							(mid 0.249642 0.249642)
							(end 0.2794 0.1778)
						)
						(arc
							(start 0.2794 -0.1778)
							(mid 0.249642 -0.249642)
							(end 0.1778 -0.2794)
						)
					)
					(width 0)
					(fill yes)
				)
			)
		)
		(pad "2" smd custom
			(at 0 0.4445 180)
			(size 0.1397 0.1397)
			(layers "F.Cu" "F.Mask" "F.Paste")
			(net "I2C_SW_EU17_ADDRESS_A0")
			(options
				(clearance outline)
				(anchor circle)
			)
			(primitives
				(gr_poly
					(pts
						(arc
							(start -0.1778 -0.2794)
							(mid -0.249642 -0.249642)
							(end -0.2794 -0.1778)
						)
						(arc
							(start -0.2794 0.1778)
							(mid -0.249642 0.249642)
							(end -0.1778 0.2794)
						)
						(arc
							(start 0.1778 0.2794)
							(mid 0.249642 0.249642)
							(end 0.2794 0.1778)
						)
						(arc
							(start 0.2794 -0.1778)
							(mid 0.249642 -0.249642)
							(end 0.1778 -0.2794)
						)
					)
					(width 0)
					(fill yes)
				)
			)
		)
	)
	(footprint ""
		(layer "F.Cu")
		(at 18.50009 -258.899914)
		(property "Reference" "LED12"
			(at 0 0 0)
			(layer "F.SilkS")
			(hide yes)
			(effects
				(font
					(size 1.27 1.27)
				)
			)
		)
		(property "Value" "LED-RB-4-GP"
			(at 5.88899 1.80848 0)
			(unlocked yes)
			(layer "F.Fab")
			(hide yes)
			(effects
				(font
					(size 1.016 1.016)
					(thickness 0.1524)
				)
			)
		)
		(property "Device Type" "LED1613-4PH20"
			(at 5.88899 0.28448 0)
			(unlocked yes)
			(layer "F.Fab")
			(hide yes)
			(effects
				(font
					(size 1.016 1.016)
					(thickness 0.1524)
				)
			)
		)
		(duplicate_pad_numbers_are_jumpers no)
		(fp_line
			(start -1.4478 -0.9652)
			(end 1.4478 -0.9652)
			(stroke
				(width 0.1524)
				(type default)
			)
			(layer "F.SilkS")
		)
		(fp_line
			(start -1.4478 0.9652)
			(end -1.4478 -0.9652)
			(stroke
				(width 0.1524)
				(type default)
			)
			(layer "F.SilkS")
		)
		(fp_line
			(start -1.4478 0.9652)
			(end -1.4478 -0.9652)
			(stroke
				(width 0.508)
				(type default)
			)
			(layer "F.SilkS")
		)
		(fp_line
			(start 1.4478 -0.9652)
			(end 1.4478 0.9652)
			(stroke
				(width 0.1524)
				(type default)
			)
			(layer "F.SilkS")
		)
		(fp_line
			(start 1.4478 0.9652)
			(end -1.4478 0.9652)
			(stroke
				(width 0.1524)
				(type default)
			)
			(layer "F.SilkS")
		)
		(fp_rect
			(start -0.8001 0.6477)
			(end 0.8001 -0.6477)
			(stroke
				(width 0)
				(type default)
			)
			(fill no)
			(layer "F.CrtYd")
		)
		(fp_poly
			(pts
				(xy -1.7018 1.2192) (xy -1.7018 -0.06223) (xy -0.8001 -0.06223) (xy -0.8001 0.6477) (xy 0.8001 0.6477)
				(xy 0.8001 -0.6477) (xy -0.8001 -0.6477) (xy -0.8001 -0.0635) (xy -1.7018 -0.0635) (xy -1.7018 -1.2192)
				(xy 1.7018 -1.2192) (xy 1.7018 1.2192)
			)
			(stroke
				(width 0)
				(type default)
			)
			(fill no)
			(layer "F.CrtYd")
		)
		(fp_rect
			(start -1.7018 1.2192)
			(end 1.7018 -1.2192)
			(stroke
				(width 0)
				(type default)
			)
			(fill no)
			(layer "F.Fab")
		)
		(pad "1" smd rect
			(at -0.73025 0.4064)
			(size 0.9144 0.6096)
			(layers "F.Cu" "F.Mask" "F.Paste")
			(net "SSD_ACT_DR12_MOS_N")
		)
		(pad "2" smd rect
			(at -0.73025 -0.4064)
			(size 0.9144 0.6096)
			(layers "F.Cu" "F.Mask" "F.Paste")
			(net "ATTN_LED_DR12_MOS_N")
		)
		(pad "3" smd rect
			(at 0.73025 -0.4064)
			(size 0.9144 0.6096)
			(layers "F.Cu" "F.Mask" "F.Paste")
			(net "DRV_ATTN_12")
		)
		(pad "4" smd rect
			(at 0.73025 0.4064)
			(size 0.9144 0.6096)
			(layers "F.Cu" "F.Mask" "F.Paste")
			(net "DRV_ACT_12")
		)
	)
	(footprint ""
		(layer "F.Cu")
		(at 102.616 -434.34 90)
		(property "Reference" "R9058"
			(at 0 0 90)
			(layer "F.SilkS")
			(hide yes)
			(effects
				(font
					(size 1.27 1.27)
				)
			)
		)
		(property "Value" "27R2F-GP"
			(at 0.064008 -3.993896 90)
			(unlocked yes)
			(layer "F.Fab")
			(hide yes)
			(effects
				(font
					(size 1.016 1.016)
					(thickness 0.1524)
				)
			)
		)
		(property "Device Type" "R402H16"
			(at 0.064008 -5.517896 90)
			(unlocked yes)
			(layer "F.Fab")
			(hide yes)
			(effects
				(font
					(size 1.016 1.016)
					(thickness 0.1524)
				)
			)
		)
		(duplicate_pad_numbers_are_jumpers no)
		(fp_line
			(start 0.508 -0.9398)
			(end -0.508 -0.9398)
			(stroke
				(width 0.1524)
				(type default)
			)
			(layer "F.SilkS")
		)
		(fp_line
			(start -0.508 -0.9398)
			(end -0.508 0.9398)
			(stroke
				(width 0.1524)
				(type default)
			)
			(layer "F.SilkS")
		)
		(fp_rect
			(start -0.508 0.9398)
			(end 0.508 -0.9398)
			(stroke
				(width 0)
				(type default)
			)
			(fill no)
			(layer "F.CrtYd")
		)
		(fp_rect
			(start -0.508 0.9398)
			(end 0.508 -0.9398)
			(stroke
				(width 0)
				(type default)
			)
			(fill no)
			(layer "F.Fab")
		)
		(pad "1" smd custom
			(at 0 -0.4445 90)
			(size 0.1397 0.1397)
			(layers "F.Cu" "F.Mask" "F.Paste")
			(net "PE_CLK_100M_DR0_2_R_N")
			(options
				(clearance outline)
				(anchor circle)
			)
			(primitives
				(gr_poly
					(pts
						(arc
							(start -0.1778 -0.2794)
							(mid -0.249642 -0.249642)
							(end -0.2794 -0.1778)
						)
						(arc
							(start -0.2794 0.1778)
							(mid -0.249642 0.249642)
							(end -0.1778 0.2794)
						)
						(arc
							(start 0.1778 0.2794)
							(mid 0.249642 0.249642)
							(end 0.2794 0.1778)
						)
						(arc
							(start 0.2794 -0.1778)
							(mid 0.249642 -0.249642)
							(end 0.1778 -0.2794)
						)
					)
					(width 0)
					(fill yes)
				)
			)
		)
		(pad "2" smd custom
			(at 0 0.4445 90)
			(size 0.1397 0.1397)
			(layers "F.Cu" "F.Mask" "F.Paste")
			(net "PE_CLK100M_DR0_2_N")
			(options
				(clearance outline)
				(anchor circle)
			)
			(primitives
				(gr_poly
					(pts
						(arc
							(start -0.1778 -0.2794)
							(mid -0.249642 -0.249642)
							(end -0.2794 -0.1778)
						)
						(arc
							(start -0.2794 0.1778)
							(mid -0.249642 0.249642)
							(end -0.1778 0.2794)
						)
						(arc
							(start 0.1778 0.2794)
							(mid 0.249642 0.249642)
							(end 0.2794 0.1778)
						)
						(arc
							(start 0.2794 -0.1778)
							(mid 0.249642 -0.249642)
							(end 0.1778 -0.2794)
						)
					)
					(width 0)
					(fill yes)
				)
			)
		)
	)
	(footprint ""
		(layer "F.Cu")
		(at 49.276 -40.132 -90)
		(property "Reference" "R9901"
			(at 0 0 270)
			(layer "F.SilkS")
			(hide yes)
			(effects
				(font
					(size 1.27 1.27)
				)
			)
		)
		(property "Value" "1K82R2F-1-GP"
			(at 0.064008 -3.993896 270)
			(unlocked yes)
			(layer "F.Fab")
			(hide yes)
			(effects
				(font
					(size 1.016 1.016)
					(thickness 0.1524)
				)
			)
		)
		(property "Device Type" "R402H16"
			(at 0.064008 -5.517896 270)
			(unlocked yes)
			(layer "F.Fab")
			(hide yes)
			(effects
				(font
					(size 1.016 1.016)
					(thickness 0.1524)
				)
			)
		)
		(duplicate_pad_numbers_are_jumpers no)
		(fp_line
			(start -0.508 -0.9398)
			(end -0.508 0.9398)
			(stroke
				(width 0.1524)
				(type default)
			)
			(layer "F.SilkS")
		)
		(fp_line
			(start 0.508 -0.9398)
			(end -0.508 -0.9398)
			(stroke
				(width 0.1524)
				(type default)
			)
			(layer "F.SilkS")
		)
		(fp_rect
			(start -0.508 0.9398)
			(end 0.508 -0.9398)
			(stroke
				(width 0)
				(type default)
			)
			(fill no)
			(layer "F.CrtYd")
		)
		(fp_rect
			(start -0.508 0.9398)
			(end 0.508 -0.9398)
			(stroke
				(width 0)
				(type default)
			)
			(fill no)
			(layer "F.Fab")
		)
		(pad "1" smd custom
			(at 0 -0.4445 270)
			(size 0.1397 0.1397)
			(layers "F.Cu" "F.Mask" "F.Paste")
			(net "P12V")
			(options
				(clearance outline)
				(anchor circle)
			)
			(primitives
				(gr_poly
					(pts
						(arc
							(start -0.1778 -0.2794)
							(mid -0.249642 -0.249642)
							(end -0.2794 -0.1778)
						)
						(arc
							(start -0.2794 0.1778)
							(mid -0.249642 0.249642)
							(end -0.1778 0.2794)
						)
						(arc
							(start 0.1778 0.2794)
							(mid 0.249642 0.249642)
							(end 0.2794 0.1778)
						)
						(arc
							(start 0.2794 -0.1778)
							(mid 0.249642 -0.249642)
							(end 0.1778 -0.2794)
						)
					)
					(width 0)
					(fill yes)
				)
			)
		)
		(pad "2" smd custom
			(at 0 0.4445 270)
			(size 0.1397 0.1397)
			(layers "F.Cu" "F.Mask" "F.Paste")
			(net "DRV_ACT_9")
			(options
				(clearance outline)
				(anchor circle)
			)
			(primitives
				(gr_poly
					(pts
						(arc
							(start -0.1778 -0.2794)
							(mid -0.249642 -0.249642)
							(end -0.2794 -0.1778)
						)
						(arc
							(start -0.2794 0.1778)
							(mid -0.249642 0.249642)
							(end -0.1778 0.2794)
						)
						(arc
							(start 0.1778 0.2794)
							(mid 0.249642 0.249642)
							(end 0.2794 0.1778)
						)
						(arc
							(start 0.2794 -0.1778)
							(mid 0.249642 -0.249642)
							(end 0.1778 -0.2794)
						)
					)
					(width 0)
					(fill yes)
				)
			)
		)
	)
	(footprint ""
		(layer "F.Cu")
		(at 209.296 -293.116 180)
		(property "Reference" "R568"
			(at 0 0 180)
			(layer "F.SilkS")
			(hide yes)
			(effects
				(font
					(size 1.27 1.27)
				)
			)
		)
		(property "Value" "300KR2F-GP"
			(at 0.064008 -3.993896 180)
			(unlocked yes)
			(layer "F.Fab")
			(hide yes)
			(effects
				(font
					(size 1.016 1.016)
					(thickness 0.1524)
				)
			)
		)
		(property "Device Type" "R402H16"
			(at 0.064008 -5.517896 180)
			(unlocked yes)
			(layer "F.Fab")
			(hide yes)
			(effects
				(font
					(size 1.016 1.016)
					(thickness 0.1524)
				)
			)
		)
		(duplicate_pad_numbers_are_jumpers no)
		(fp_line
			(start 0.508 -0.9398)
			(end -0.508 -0.9398)
			(stroke
				(width 0.1524)
				(type default)
			)
			(layer "F.SilkS")
		)
		(fp_line
			(start -0.508 -0.9398)
			(end -0.508 0.9398)
			(stroke
				(width 0.1524)
				(type default)
			)
			(layer "F.SilkS")
		)
		(fp_rect
			(start -0.508 0.9398)
			(end 0.508 -0.9398)
			(stroke
				(width 0)
				(type default)
			)
			(fill no)
			(layer "F.CrtYd")
		)
		(fp_rect
			(start -0.508 0.9398)
			(end 0.508 -0.9398)
			(stroke
				(width 0)
				(type default)
			)
			(fill no)
			(layer "F.Fab")
		)
		(pad "1" smd custom
			(at 0 -0.4445 180)
			(size 0.1397 0.1397)
			(layers "F.Cu" "F.Mask" "F.Paste")
			(net "SW_SSD2_N")
			(options
				(clearance outline)
				(anchor circle)
			)
			(primitives
				(gr_poly
					(pts
						(arc
							(start -0.1778 -0.2794)
							(mid -0.249642 -0.249642)
							(end -0.2794 -0.1778)
						)
						(arc
							(start -0.2794 0.1778)
							(mid -0.249642 0.249642)
							(end -0.1778 0.2794)
						)
						(arc
							(start 0.1778 0.2794)
							(mid 0.249642 0.249642)
							(end 0.2794 0.1778)
						)
						(arc
							(start 0.2794 -0.1778)
							(mid 0.249642 -0.249642)
							(end 0.1778 -0.2794)
						)
					)
					(width 0)
					(fill yes)
				)
			)
		)
		(pad "2" smd custom
			(at 0 0.4445 180)
			(size 0.1397 0.1397)
			(layers "F.Cu" "F.Mask" "F.Paste")
			(net "P12V")
			(options
				(clearance outline)
				(anchor circle)
			)
			(primitives
				(gr_poly
					(pts
						(arc
							(start -0.1778 -0.2794)
							(mid -0.249642 -0.249642)
							(end -0.2794 -0.1778)
						)
						(arc
							(start -0.2794 0.1778)
							(mid -0.249642 0.249642)
							(end -0.1778 0.2794)
						)
						(arc
							(start 0.1778 0.2794)
							(mid 0.249642 0.249642)
							(end 0.2794 0.1778)
						)
						(arc
							(start 0.2794 -0.1778)
							(mid 0.249642 -0.249642)
							(end 0.1778 -0.2794)
						)
					)
					(width 0)
					(fill yes)
				)
			)
		)
	)
	(footprint ""
		(layer "F.Cu")
		(at 99.06 -204.851 90)
		(property "Reference" "C8863"
			(at 0 0 90)
			(layer "F.SilkS")
			(hide yes)
			(effects
				(font
					(size 1.27 1.27)
				)
			)
		)
		(property "Value" "SCD1U16V2KX-3GP"
			(at 1.1811 -2.7051 90)
			(unlocked yes)
			(layer "F.Fab")
			(hide yes)
			(effects
				(font
					(size 1.016 1.016)
					(thickness 0.1524)
				)
			)
		)
		(property "Device Type" "C402H22"
			(at 1.1811 -4.2291 90)
			(unlocked yes)
			(layer "F.Fab")
			(hide yes)
			(effects
				(font
					(size 1.016 1.016)
					(thickness 0.1524)
				)
			)
		)
		(duplicate_pad_numbers_are_jumpers no)
		(fp_rect
			(start -0.4318 0.9525)
			(end 0.4318 -0.9525)
			(stroke
				(width 0)
				(type default)
			)
			(fill no)
			(layer "F.CrtYd")
		)
		(fp_rect
			(start -0.4318 0.9525)
			(end 0.4318 -0.9525)
			(stroke
				(width 0)
				(type default)
			)
			(fill no)
			(layer "F.Fab")
		)
		(pad "1" smd custom
			(at 0 -0.4445 90)
			(size 0.1524 0.1524)
			(layers "F.Cu" "F.Mask" "F.Paste")
			(net "VDD_IO_3")
			(options
				(clearance outline)
				(anchor circle)
			)
			(primitives
				(gr_poly
					(pts
						(arc
							(start 0.3048 -0.2032)
							(mid 0.275042 -0.275042)
							(end 0.2032 -0.3048)
						)
						(arc
							(start -0.2032 -0.3048)
							(mid -0.275042 -0.275042)
							(end -0.3048 -0.2032)
						)
						(arc
							(start -0.3048 0.2032)
							(mid -0.275042 0.275042)
							(end -0.2032 0.3048)
						)
						(arc
							(start 0.2032 0.3048)
							(mid 0.275042 0.275042)
							(end 0.3048 0.2032)
						)
					)
					(width 0)
					(fill yes)
				)
			)
		)
		(pad "2" smd custom
			(at 0 0.4445 90)
			(size 0.1524 0.1524)
			(layers "F.Cu" "F.Mask" "F.Paste")
			(net "GND")
			(options
				(clearance outline)
				(anchor circle)
			)
			(primitives
				(gr_poly
					(pts
						(arc
							(start 0.3048 -0.2032)
							(mid 0.275042 -0.275042)
							(end 0.2032 -0.3048)
						)
						(arc
							(start -0.2032 -0.3048)
							(mid -0.275042 -0.275042)
							(end -0.3048 -0.2032)
						)
						(arc
							(start -0.3048 0.2032)
							(mid -0.275042 0.275042)
							(end -0.2032 0.3048)
						)
						(arc
							(start 0.2032 0.3048)
							(mid 0.275042 0.275042)
							(end 0.3048 0.2032)
						)
					)
					(width 0)
					(fill yes)
				)
			)
		)
	)
)
